(kicad_pcb
	(version 20241229)
	(generator "pcbnew")
	(generator_version "9.0")
	(general
		(thickness 1.711)
		(legacy_teardrops no)
	)
	(paper "A4")
	(title_block
		(title "Antmicro Baseboard for Jetson AGX Thor")
		(date "2026-02-18")
		(rev "1.1.0")
		(company "Antmicro Ltd")
		(comment 1 "www.antmicro.com")
		(comment 9 "footprints 739-743 of 1170")
	)
	(layers
		(0 "F.Cu" signal)
		(4 "In1.Cu" signal)
		(6 "In2.Cu" signal)
		(8 "In3.Cu" signal)
		(10 "In4.Cu" jumper)
		(12 "In5.Cu" signal)
		(14 "In6.Cu" signal)
		(16 "In7.Cu" signal)
		(18 "In8.Cu" signal)
		(2 "B.Cu" signal)
		(9 "F.Adhes" user "F.Adhesive")
		(11 "B.Adhes" user "B.Adhesive")
		(13 "F.Paste" user)
		(15 "B.Paste" user)
		(5 "F.SilkS" user "F.Silkscreen")
		(7 "B.SilkS" user "B.Silkscreen")
		(1 "F.Mask" user)
		(3 "B.Mask" user)
		(17 "Dwgs.User" user "User.Drawings")
		(19 "Cmts.User" user "User.Comments")
		(21 "Eco1.User" user "User.Eco1")
		(23 "Eco2.User" user "User.Eco2")
		(25 "Edge.Cuts" user)
		(27 "Margin" user)
		(31 "F.CrtYd" user "F.Courtyard")
		(29 "B.CrtYd" user "B.Courtyard")
		(35 "F.Fab" user)
		(33 "B.Fab" user)
	)
	(footprint "antmicro-footprints:LED_0603_1608Metric_G"
		(layer "B.Cu")
		(at 133.2 55.3 -90)
		(descr "LED SMD 0603 Green")
		(tags "LED SMD 0603 Green")
		(property "Reference" "D41"
			(at -1.08 1.82 90)
			(layer "B.SilkS")
			(effects
				(font
					(size 0.7 0.7)
					(thickness 0.15)
				)
				(justify left bottom mirror)
			)
		)
		(property "Value" "LED_G_0603_LTST-C190GKT"
			(at -0.001 -1.599 90)
			(layer "B.Fab")
			(effects
				(font
					(size 0.7 0.7)
					(thickness 0.15)
				)
				(justify left bottom mirror)
			)
		)
		(property "Datasheet" "https://media.digikey.com/pdf/Data%20Sheets/Lite-On%20PDFs/LTST-C190GKT.pdf"
			(at 0 0 90)
			(layer "B.Fab")
			(hide yes)
			(effects
				(font
					(size 1.27 1.27)
					(thickness 0.15)
				)
				(justify mirror)
			)
		)
		(property "Description" "LED, Green, SMD, 0603, 20 mA, 2.1 V, 569 nm"
			(at 0 0 90)
			(layer "B.Fab")
			(hide yes)
			(effects
				(font
					(size 1.27 1.27)
					(thickness 0.15)
				)
				(justify mirror)
			)
		)
		(property "MPN" "LTST-C190GKT"
			(at 0 0 90)
			(unlocked yes)
			(layer "B.Fab")
			(hide yes)
			(effects
				(font
					(size 1 1)
					(thickness 0.15)
				)
				(justify mirror)
			)
		)
		(property "Manufacturer" "Lite-On"
			(at 0 0 90)
			(unlocked yes)
			(layer "B.Fab")
			(hide yes)
			(effects
				(font
					(size 1 1)
					(thickness 0.15)
				)
				(justify mirror)
			)
		)
		(property "Author" "Antmicro"
			(at 0 0 90)
			(unlocked yes)
			(layer "B.Fab")
			(hide yes)
			(effects
				(font
					(size 1 1)
					(thickness 0.15)
				)
				(justify mirror)
			)
		)
		(property "License" "Apache-2.0"
			(at 0 0 90)
			(unlocked yes)
			(layer "B.Fab")
			(hide yes)
			(effects
				(font
					(size 1 1)
					(thickness 0.15)
				)
				(justify mirror)
			)
		)
		(property "Color" "Green"
			(at 0 0 90)
			(unlocked yes)
			(layer "B.Fab")
			(hide yes)
			(effects
				(font
					(size 1 1)
					(thickness 0.15)
				)
				(justify mirror)
			)
		)
		(sheetname "/Peripherals/")
		(sheetfile "peripherals.kicad_sch")
		(attr smd)
		(fp_line
			(start 0.22 0.35)
			(end -0.22 0.35)
			(stroke
				(width 0.15)
				(type solid)
			)
			(layer "B.SilkS")
		)
		(fp_line
			(start -1.18 0.319)
			(end -1.18 -0.321)
			(stroke
				(width 0.15)
				(type solid)
			)
			(layer "B.SilkS")
		)
		(fp_line
			(start -0.094672 -0.001008)
			(end 0.105328 0.198992)
			(stroke
				(width 0.1)
				(type solid)
			)
			(layer "B.SilkS")
		)
		(fp_line
			(start -0.094672 -0.001008)
			(end -0.24 -0.001008)
			(stroke
				(width 0.1)
				(type solid)
			)
			(layer "B.SilkS")
		)
		(fp_line
			(start 0.105328 -0.001008)
			(end 0.24 -0.001)
			(stroke
				(width 0.1)
				(type solid)
			)
			(layer "B.SilkS")
		)
		(fp_line
			(start -0.094672 -0.201008)
			(end -0.094672 0.198992)
			(stroke
				(width 0.1)
				(type solid)
			)
			(layer "B.SilkS")
		)
		(fp_line
			(start 0.105328 -0.201008)
			(end 0.105328 0.198992)
			(stroke
				(width 0.1)
				(type solid)
			)
			(layer "B.SilkS")
		)
		(fp_line
			(start 0.105328 -0.201008)
			(end -0.094672 -0.001008)
			(stroke
				(width 0.1)
				(type solid)
			)
			(layer "B.SilkS")
		)
		(fp_line
			(start 0.22 -0.35)
			(end -0.22 -0.35)
			(stroke
				(width 0.15)
				(type solid)
			)
			(layer "B.SilkS")
		)
		(fp_rect
			(start 1.25 -0.65)
			(end -1.25 0.65)
			(stroke
				(width 0.05)
				(type solid)
			)
			(fill no)
			(layer "B.CrtYd")
		)
		(fp_line
			(start -0.199 0.202)
			(end -0.199 -0.1)
			(stroke
				(width 0.15)
				(type solid)
			)
			(layer "B.Fab")
		)
		(fp_line
			(start 0.201 0.202)
			(end -0.101 0)
			(stroke
				(width 0.15)
				(type solid)
			)
			(layer "B.Fab")
		)
		(fp_line
			(start -0.199 0)
			(end -0.597 0)
			(stroke
				(width 0.15)
				(type solid)
			)
			(layer "B.Fab")
		)
		(fp_line
			(start -0.101 0)
			(end 0.201 -0.2)
			(stroke
				(width 0.15)
				(type solid)
			)
			(layer "B.Fab")
		)
		(fp_line
			(start 0.201 0)
			(end 0.201 0.202)
			(stroke
				(width 0.15)
				(type solid)
			)
			(layer "B.Fab")
		)
		(fp_line
			(start 0.599 0)
			(end 0.201 0)
			(stroke
				(width 0.15)
				(type solid)
			)
			(layer "B.Fab")
		)
		(fp_line
			(start -0.199 -0.2)
			(end -0.199 -0.1)
			(stroke
				(width 0.15)
				(type solid)
			)
			(layer "B.Fab")
		)
		(fp_line
			(start 0.201 -0.2)
			(end 0.201 0)
			(stroke
				(width 0.15)
				(type solid)
			)
			(layer "B.Fab")
		)
		(fp_rect
			(start 0.848 -0.4)
			(end -0.85 0.402)
			(stroke
				(width 0.15)
				(type solid)
			)
			(fill no)
			(layer "B.Fab")
		)
		(fp_text user "License: Apache-2.0"
			(at -1.4224 -3.599 90)
			(layer "B.Fab")
			(effects
				(font
					(size 0.7 0.7)
					(thickness 0.15)
				)
				(justify left bottom mirror)
			)
		)
		(fp_text user "${REFERENCE}"
			(at -1.4224 -5.999 90)
			(layer "B.Fab")
			(effects
				(font
					(size 0.7 0.7)
					(thickness 0.15)
				)
				(justify left bottom mirror)
			)
		)
		(fp_text user "Author: Antmicro"
			(at -1.4224 -4.799 90)
			(layer "B.Fab")
			(effects
				(font
					(size 0.7 0.7)
					(thickness 0.15)
				)
				(justify left bottom mirror)
			)
		)
		(pad "1" smd roundrect
			(at -0.7 0 90)
			(size 0.8 1)
			(layers "B.Cu" "B.Mask" "B.Paste")
			(roundrect_rratio 0.2)
			(net 1 "GND")
			(pinfunction "C")
			(pintype "passive")
		)
		(pad "2" smd roundrect
			(at 0.7 0 90)
			(size 0.8 1)
			(layers "B.Cu" "B.Mask" "B.Paste")
			(roundrect_rratio 0.2)
			(net 547 "Net-(D41-A)")
			(pinfunction "A")
			(pintype "passive")
		)
	)
	(footprint "antmicro-footprints:C_0402_1005Metric"
		(layer "B.Cu")
		(at 105.98 70.66)
		(descr "Capacitor SMD 0402")
		(tags "capacitor SMD 0402")
		(property "Reference" "C3"
			(at -0.68 0.64 0)
			(layer "B.SilkS")
			(effects
				(font
					(size 0.7 0.7)
					(thickness 0.15)
				)
				(justify right top mirror)
			)
		)
		(property "Value" "C_10u_0402"
			(at -1.022927 -2.155213 0)
			(layer "B.Fab")
			(effects
				(font
					(size 0.7 0.7)
					(thickness 0.15)
				)
				(justify right top mirror)
			)
		)
		(property "Datasheet" "https://www.yageo.com/en/Chart/Download/pdf/CC0402MRX5R5BB106"
			(at 0 0 0)
			(layer "B.Fab")
			(hide yes)
			(effects
				(font
					(size 1.27 1.27)
					(thickness 0.15)
				)
				(justify mirror)
			)
		)
		(property "Description" "SMD Multilayer Ceramic Capacitor, 10 µF, 6.3 V, 0402 [1005 Metric], ± 20%, X5R, CC Series"
			(at 0 0 0)
			(layer "B.Fab")
			(hide yes)
			(effects
				(font
					(size 1.27 1.27)
					(thickness 0.15)
				)
				(justify mirror)
			)
		)
		(property "MPN" "CC0402MRX5R5BB106"
			(at 0 0 180)
			(unlocked yes)
			(layer "B.Fab")
			(hide yes)
			(effects
				(font
					(size 1 1)
					(thickness 0.15)
				)
				(justify mirror)
			)
		)
		(property "Manufacturer" "YAGEO"
			(at 0 0 180)
			(unlocked yes)
			(layer "B.Fab")
			(hide yes)
			(effects
				(font
					(size 1 1)
					(thickness 0.15)
				)
				(justify mirror)
			)
		)
		(property "License" "Apache-2.0"
			(at 0 0 180)
			(unlocked yes)
			(layer "B.Fab")
			(hide yes)
			(effects
				(font
					(size 1 1)
					(thickness 0.15)
				)
				(justify mirror)
			)
		)
		(property "Author" "Antmicro"
			(at 0 0 180)
			(unlocked yes)
			(layer "B.Fab")
			(hide yes)
			(effects
				(font
					(size 1 1)
					(thickness 0.15)
				)
				(justify mirror)
			)
		)
		(property "Val" "10u"
			(at 0 0 180)
			(unlocked yes)
			(layer "B.Fab")
			(hide yes)
			(effects
				(font
					(size 1 1)
					(thickness 0.15)
				)
				(justify mirror)
			)
		)
		(property "Voltage" ""
			(at 0 0 180)
			(unlocked yes)
			(layer "B.Fab")
			(hide yes)
			(effects
				(font
					(size 1 1)
					(thickness 0.15)
				)
				(justify mirror)
			)
		)
		(property "Dielectric" "template_dielectric"
			(at 0 0 180)
			(unlocked yes)
			(layer "B.Fab")
			(hide yes)
			(effects
				(font
					(size 1 1)
					(thickness 0.15)
				)
				(justify mirror)
			)
		)
		(sheetname "/SoM_Power/")
		(sheetfile "som_power.kicad_sch")
		(attr smd)
		(fp_rect
			(start -0.925 0.47)
			(end 0.925 -0.47)
			(stroke
				(width 0.05)
				(type default)
			)
			(fill no)
			(layer "B.CrtYd")
		)
		(fp_line
			(start -0.494 -0.248)
			(end -0.494 0.25)
			(stroke
				(width 0.15)
				(type solid)
			)
			(layer "B.Fab")
		)
		(fp_line
			(start -0.494 0.25)
			(end 0.504 0.25)
			(stroke
				(width 0.15)
				(type solid)
			)
			(layer "B.Fab")
		)
		(fp_line
			(start 0.504 -0.248)
			(end -0.494 -0.248)
			(stroke
				(width 0.15)
				(type solid)
			)
			(layer "B.Fab")
		)
		(fp_line
			(start 0.504 0.25)
			(end 0.504 -0.248)
			(stroke
				(width 0.15)
				(type solid)
			)
			(layer "B.Fab")
		)
		(fp_text user "Author: Antmicro"
			(at -0.939 -3.399 0)
			(layer "B.Fab")
			(effects
				(font
					(size 0.7 0.7)
					(thickness 0.15)
				)
				(justify right top mirror)
			)
		)
		(fp_text user "${REFERENCE}"
			(at -0.939 -4.599 0)
			(layer "B.Fab")
			(effects
				(font
					(size 0.7 0.7)
					(thickness 0.15)
				)
				(justify right top mirror)
			)
		)
		(fp_text user "License: Apache-2.0"
			(at -0.939 -5.799 0)
			(layer "B.Fab")
			(effects
				(font
					(size 0.7 0.7)
					(thickness 0.15)
				)
				(justify right top mirror)
			)
		)
		(pad "1" smd roundrect
			(at -0.48 0)
			(size 0.59 0.64)
			(layers "B.Cu" "B.Mask" "B.Paste")
			(roundrect_rratio 0.25)
			(net 1 "GND")
			(pintype "passive")
		)
		(pad "2" smd roundrect
			(at 0.48 0)
			(size 0.59 0.64)
			(layers "B.Cu" "B.Mask" "B.Paste")
			(roundrect_rratio 0.25)
			(net 213 "+5V_SOM")
			(pintype "passive")
		)
	)
	(footprint "antmicro-footprints:R_0402_1005Metric"
		(layer "B.Cu")
		(at 99 67.25)
		(descr "Resistor SMD 0402")
		(tags "resistor SMD 0402")
		(property "Reference" "R50"
			(at -1.122484 0.772697 0)
			(layer "B.SilkS")
			(effects
				(font
					(size 0.7 0.7)
					(thickness 0.15)
				)
				(justify right top mirror)
			)
		)
		(property "Value" "R_470R_0402"
			(at -1.011843 -1.772047 0)
			(layer "B.Fab")
			(effects
				(font
					(size 0.7 0.7)
					(thickness 0.15)
				)
				(justify right top mirror)
			)
		)
		(property "Datasheet" "https://www.bourns.com/docs/product-datasheets/cr.pdf"
			(at 0 0 0)
			(layer "B.Fab")
			(hide yes)
			(effects
				(font
					(size 1.27 1.27)
					(thickness 0.15)
				)
				(justify mirror)
			)
		)
		(property "Description" "SMD Chip Resistor, 470 ohm, ± 1%, 62.5 mW, 0402 [1005 Metric], Thick Film, General Purpose"
			(at 0 0 0)
			(layer "B.Fab")
			(hide yes)
			(effects
				(font
					(size 1.27 1.27)
					(thickness 0.15)
				)
				(justify mirror)
			)
		)
		(property "MPN" "CR0402-FX-4700GLF"
			(at 0 0 180)
			(unlocked yes)
			(layer "B.Fab")
			(hide yes)
			(effects
				(font
					(size 1 1)
					(thickness 0.15)
				)
				(justify mirror)
			)
		)
		(property "Manufacturer" "Bourns"
			(at 0 0 180)
			(unlocked yes)
			(layer "B.Fab")
			(hide yes)
			(effects
				(font
					(size 1 1)
					(thickness 0.15)
				)
				(justify mirror)
			)
		)
		(property "License" "Apache-2.0"
			(at 0 0 180)
			(unlocked yes)
			(layer "B.Fab")
			(hide yes)
			(effects
				(font
					(size 1 1)
					(thickness 0.15)
				)
				(justify mirror)
			)
		)
		(property "Author" "Antmicro"
			(at 0 0 180)
			(unlocked yes)
			(layer "B.Fab")
			(hide yes)
			(effects
				(font
					(size 1 1)
					(thickness 0.15)
				)
				(justify mirror)
			)
		)
		(property "Val" "470R"
			(at 0 0 180)
			(unlocked yes)
			(layer "B.Fab")
			(hide yes)
			(effects
				(font
					(size 1 1)
					(thickness 0.15)
				)
				(justify mirror)
			)
		)
		(property "Tolerance" "1%"
			(at 0 0 180)
			(unlocked yes)
			(layer "B.Fab")
			(hide yes)
			(effects
				(font
					(size 1 1)
					(thickness 0.15)
				)
				(justify mirror)
			)
		)
		(sheetname "/SoM_Power/")
		(sheetfile "som_power.kicad_sch")
		(attr smd)
		(fp_rect
			(start -0.925 0.47)
			(end 0.925 -0.47)
			(stroke
				(width 0.05)
				(type default)
			)
			(fill no)
			(layer "B.CrtYd")
		)
		(fp_rect
			(start -0.5 0.25)
			(end 0.5 -0.25)
			(stroke
				(width 0.15)
				(type solid)
			)
			(fill no)
			(layer "B.Fab")
		)
		(fp_text user "License: Apache-2.0"
			(at -0.95 -5.169 0)
			(layer "B.Fab")
			(effects
				(font
					(size 0.7 0.7)
					(thickness 0.15)
				)
				(justify right top mirror)
			)
		)
		(fp_text user "${REFERENCE}"
			(at -0.95 -3.168 0)
			(layer "B.Fab")
			(effects
				(font
					(size 0.7 0.7)
					(thickness 0.15)
				)
				(justify right top mirror)
			)
		)
		(fp_text user "Author: Antmicro"
			(at -0.95 -4.169 0)
			(layer "B.Fab")
			(effects
				(font
					(size 0.7 0.7)
					(thickness 0.15)
				)
				(justify right top mirror)
			)
		)
		(pad "1" smd roundrect
			(at -0.48 0)
			(size 0.59 0.64)
			(layers "B.Cu" "B.Mask" "B.Paste")
			(roundrect_rratio 0.25)
			(net 1302 "Net-(Q37-D)")
			(pintype "passive")
		)
		(pad "2" smd roundrect
			(at 0.48 0)
			(size 0.59 0.64)
			(layers "B.Cu" "B.Mask" "B.Paste")
			(roundrect_rratio 0.25)
			(net 213 "+5V_SOM")
			(pintype "passive")
		)
	)
	(footprint "antmicro-footprints:TP_SMD_0.75mm"
		(layer "B.Cu")
		(at 133.2 72.6 -90)
		(property "Reference" "TP108"
			(at 0.5 0.4 0)
			(layer "B.SilkS")
			(effects
				(font
					(size 0.7 0.7)
					(thickness 0.15)
				)
				(justify left bottom mirror)
			)
		)
		(property "Value" "TP_0.75mm_SMD"
			(at 0 -1.2 90)
			(layer "B.Fab")
			(effects
				(font
					(size 0.7 0.7)
					(thickness 0.15)
				)
				(justify left bottom mirror)
			)
		)
		(property "Description" "SMT test point"
			(at 0 0 90)
			(layer "B.Fab")
			(hide yes)
			(effects
				(font
					(size 1.27 1.27)
					(thickness 0.15)
				)
				(justify mirror)
			)
		)
		(property "MPN" ""
			(at 0 0 90)
			(unlocked yes)
			(layer "B.Fab")
			(hide yes)
			(effects
				(font
					(size 1 1)
					(thickness 0.15)
				)
				(justify mirror)
			)
		)
		(property "Manufacturer" ""
			(at 0 0 90)
			(unlocked yes)
			(layer "B.Fab")
			(hide yes)
			(effects
				(font
					(size 1 1)
					(thickness 0.15)
				)
				(justify mirror)
			)
		)
		(property "Author" "Antmicro"
			(at 0 0 90)
			(unlocked yes)
			(layer "B.Fab")
			(hide yes)
			(effects
				(font
					(size 1 1)
					(thickness 0.15)
				)
				(justify mirror)
			)
		)
		(property "License" "Apache-2.0"
			(at 0 0 90)
			(unlocked yes)
			(layer "B.Fab")
			(hide yes)
			(effects
				(font
					(size 1 1)
					(thickness 0.15)
				)
				(justify mirror)
			)
		)
		(sheetname "/SoM_IO/")
		(sheetfile "som_io.kicad_sch")
		(attr exclude_from_pos_files exclude_from_bom)
		(fp_circle
			(center 0 0)
			(end 0.475 0)
			(stroke
				(width 0.05)
				(type default)
			)
			(fill no)
			(layer "B.CrtYd")
		)
		(fp_text user "License: Apache-2.0"
			(at -0.4 -5.101 90)
			(layer "B.Fab")
			(effects
				(font
					(size 0.7 0.7)
					(thickness 0.15)
				)
				(justify left bottom mirror)
			)
		)
		(fp_text user "${REFERENCE}"
			(at -0.4 -2.7 90)
			(layer "B.Fab")
			(effects
				(font
					(size 0.7 0.7)
					(thickness 0.15)
				)
				(justify left bottom mirror)
			)
		)
		(fp_text user "Author: Antmicro"
			(at -0.4 -3.901 90)
			(layer "B.Fab")
			(effects
				(font
					(size 0.7 0.7)
					(thickness 0.15)
				)
				(justify left bottom mirror)
			)
		)
		(pad "1" smd circle
			(at 0 0 270)
			(size 0.75 0.75)
			(layers "B.Cu" "B.Mask")
			(net 108 "/SoM_IO/UART1.RX")
			(pinfunction "1")
			(pintype "passive")
		)
	)
	(footprint "antmicro-footprints:R_0402_1005Metric"
		(layer "B.Cu")
		(at 212.8 87.7)
		(descr "Resistor SMD 0402")
		(tags "resistor SMD 0402")
		(property "Reference" "R131"
			(at -3.9 -0.3 0)
			(layer "B.SilkS")
			(effects
				(font
					(size 0.7 0.7)
					(thickness 0.15)
				)
				(justify right top mirror)
			)
		)
		(property "Value" "R_1k_0402"
			(at -1.011843 -1.772046 0)
			(layer "B.Fab")
			(effects
				(font
					(size 0.7 0.7)
					(thickness 0.15)
				)
				(justify right top mirror)
			)
		)
		(property "Datasheet" "https://www.bourns.com/docs/product-datasheets/cr.pdf"
			(at 0 0 0)
			(layer "B.Fab")
			(hide yes)
			(effects
				(font
					(size 1.27 1.27)
					(thickness 0.15)
				)
				(justify mirror)
			)
		)
		(property "Description" "SMD Chip Resistor, 1 kohm, ± 1%, 63 mW, 0402 [1005 Metric], Thick Film, General Purpose"
			(at 0 0 0)
			(layer "B.Fab")
			(hide yes)
			(effects
				(font
					(size 1.27 1.27)
					(thickness 0.15)
				)
				(justify mirror)
			)
		)
		(property "Manufacturer" "Bourns"
			(at 0 0 180)
			(unlocked yes)
			(layer "B.Fab")
			(hide yes)
			(effects
				(font
					(size 1 1)
					(thickness 0.15)
				)
				(justify mirror)
			)
		)
		(property "MPN" "CR0402-FX-1001GLF"
			(at 0 0 180)
			(unlocked yes)
			(layer "B.Fab")
			(hide yes)
			(effects
				(font
					(size 1 1)
					(thickness 0.15)
				)
				(justify mirror)
			)
		)
		(property "Val" "1k"
			(at 0 0 180)
			(unlocked yes)
			(layer "B.Fab")
			(hide yes)
			(effects
				(font
					(size 1 1)
					(thickness 0.15)
				)
				(justify mirror)
			)
		)
		(property "License" "Apache-2.0"
			(at 0 0 180)
			(unlocked yes)
			(layer "B.Fab")
			(hide yes)
			(effects
				(font
					(size 1 1)
					(thickness 0.15)
				)
				(justify mirror)
			)
		)
		(property "Author" "Antmicro"
			(at 0 0 180)
			(unlocked yes)
			(layer "B.Fab")
			(hide yes)
			(effects
				(font
					(size 1 1)
					(thickness 0.15)
				)
				(justify mirror)
			)
		)
		(property "Tolerance" "1%"
			(at 0 0 180)
			(unlocked yes)
			(layer "B.Fab")
			(hide yes)
			(effects
				(font
					(size 1 1)
					(thickness 0.15)
				)
				(justify mirror)
			)
		)
		(sheetname "/USB DP Alt mode/")
		(sheetfile "usb_dp.kicad_sch")
		(attr smd exclude_from_pos_files exclude_from_bom dnp)
		(fp_poly
			(pts
				(xy -0.925 0.47) (xy 0.925 0.47) (xy 0.925 -0.47) (xy -0.925 -0.47)
			)
			(stroke
				(width 0.05)
				(type default)
			)
			(fill no)
			(layer "B.CrtYd")
		)
		(fp_poly
			(pts
				(xy -0.5 0.25) (xy 0.5 0.25) (xy 0.5 -0.25) (xy -0.5 -0.25)
			)
			(stroke
				(width 0.15)
				(type solid)
			)
			(fill no)
			(layer "B.Fab")
		)
		(fp_text user "${REFERENCE}"
			(at -0.95 -3.168 0)
			(layer "B.Fab")
			(effects
				(font
					(size 0.7 0.7)
					(thickness 0.15)
				)
				(justify right top mirror)
			)
		)
		(fp_text user "Author: Antmicro"
			(at -0.95 -4.169 0)
			(layer "B.Fab")
			(effects
				(font
					(size 0.7 0.7)
					(thickness 0.15)
				)
				(justify right top mirror)
			)
		)
		(fp_text user "License: Apache-2.0"
			(at -0.949999 -5.169 0)
			(layer "B.Fab")
			(effects
				(font
					(size 0.7 0.7)
					(thickness 0.15)
				)
				(justify right top mirror)
			)
		)
		(pad "1" smd roundrect
			(at -0.48 0)
			(size 0.59 0.64)
			(layers "B.Cu" "B.Mask" "B.Paste")
			(roundrect_rratio 0.25)
			(net 964 "/USB DP Alt mode/USBC1_SSEQ0")
			(pintype "passive")
		)
		(pad "2" smd roundrect
			(at 0.48 0)
			(size 0.59 0.64)
			(layers "B.Cu" "B.Mask" "B.Paste")
			(roundrect_rratio 0.25)
			(net 1 "GND")
			(pintype "passive")
		)
	)
)
